(kicad_pcb
	(version 20260206)
	(generator "pcbnew")
	(generator_version "10.0")
	(general
		(thickness 1.6)
		(legacy_teardrops no)
	)
	(paper "A4")
	(title_block
		(title "04192023_DAF0TMB3IC0_F0TG_MB_C_brd_V02_OCP.brd")
		(comment 1 "Grand Teton / footprints 1936-1939 of 8354")
	)
	(layers
		(0 "F.Cu" signal "TOP")
		(4 "In1.Cu" signal "GND")
		(6 "In2.Cu" signal "IN1")
		(8 "In3.Cu" signal "GND1")
		(10 "In4.Cu" signal "IN2")
		(12 "In5.Cu" signal "GND2")
		(14 "In6.Cu" signal "IN3")
		(16 "In7.Cu" signal "GND3")
		(18 "In8.Cu" signal "VCC")
		(20 "In9.Cu" signal "VCC1")
		(22 "In10.Cu" signal "GND4")
		(24 "In11.Cu" signal "IN4")
		(26 "In12.Cu" signal "GND5")
		(28 "In13.Cu" signal "IN5")
		(30 "In14.Cu" signal "GND6")
		(32 "In15.Cu" signal "IN6")
		(34 "In16.Cu" signal "GND7")
		(2 "B.Cu" signal "BOTTOM")
		(9 "F.Adhes" user "F.Adhesive")
		(11 "B.Adhes" user "B.Adhesive")
		(13 "F.Paste" user "Package Geometry/Pastemask Top")
		(15 "B.Paste" user "Package Geometry/Pastemask Bottom")
		(5 "F.SilkS" user "Ref Des/Silkscreen Top")
		(7 "B.SilkS" user "Ref Des/Silkscreen Bottom")
		(1 "F.Mask" user "Board Geometry/Soldermask Top")
		(3 "B.Mask" user "Board Geometry/Soldermask Bottom")
		(17 "Dwgs.User" user "User.Drawings")
		(19 "Cmts.User" user "User.Comments")
		(21 "Eco1.User" user "User.Eco1")
		(23 "Eco2.User" user "User.Eco2")
		(25 "Edge.Cuts" user "Board Geometry/Outline")
		(27 "Margin" user)
		(31 "F.CrtYd" user "Package Geometry/Place Bound Top")
		(29 "B.CrtYd" user "Package Geometry/Place Bound Bottom")
		(35 "F.Fab" user "Ref Des/Assembly Top")
		(33 "B.Fab" user "Ref Des/Assembly Bottom")
	)
	(footprint ""
		(layer "F.Cu")
		(at 115.68557 -171.923456 180)
		(property "Reference" "PU30"
			(at 2.49682 -7.206742 0)
			(unlocked yes)
			(layer "F.SilkS")
			(effects
				(font
					(size 0.7874 0.5842)
					(thickness 0.1524)
				)
				(justify left)
			)
		)
		(property "Value" ""
			(at 0 0 180)
			(layer "F.Fab")
			(effects
				(font
					(size 1.27 1.27)
				)
			)
		)
		(duplicate_pad_numbers_are_jumpers no)
		(fp_line
			(start 2.500122 2.999994)
			(end 2.2987 2.999994)
			(stroke
				(width 0.1524)
				(type default)
			)
			(layer "F.SilkS")
		)
		(fp_line
			(start 2.500122 2.339594)
			(end 2.500122 2.999994)
			(stroke
				(width 0.1524)
				(type default)
			)
			(layer "F.SilkS")
		)
		(fp_line
			(start 2.500122 -2.999994)
			(end 2.500122 -2.44348)
			(stroke
				(width 0.1524)
				(type default)
			)
			(layer "F.SilkS")
		)
		(fp_line
			(start 2.31394 -2.999994)
			(end 2.500122 -2.999994)
			(stroke
				(width 0.1524)
				(type default)
			)
			(layer "F.SilkS")
		)
		(fp_line
			(start -2.2987 2.999994)
			(end -2.500122 2.999994)
			(stroke
				(width 0.1524)
				(type default)
			)
			(layer "F.SilkS")
		)
		(fp_line
			(start -2.500122 2.999994)
			(end -2.500122 2.339594)
			(stroke
				(width 0.1524)
				(type default)
			)
			(layer "F.SilkS")
		)
		(fp_line
			(start -2.500122 0.6604)
			(end -2.500122 0.229108)
			(stroke
				(width 0.1524)
				(type default)
			)
			(layer "F.SilkS")
		)
		(fp_line
			(start -2.500122 -2.529078)
			(end -2.500122 -2.999994)
			(stroke
				(width 0.1524)
				(type default)
			)
			(layer "F.SilkS")
		)
		(fp_line
			(start -2.500122 -2.999994)
			(end -2.24409 -2.999994)
			(stroke
				(width 0.1524)
				(type default)
			)
			(layer "F.SilkS")
		)
		(fp_poly
			(pts
				(xy -2.781554 -2.38633) (xy -3.455162 -2.610866) (xy -3.00609 -3.059938)
			)
			(stroke
				(width 0)
				(type default)
			)
			(fill yes)
			(layer "F.SilkS")
		)
		(fp_line
			(start 2.500122 2.999994)
			(end -2.500122 2.999994)
			(stroke
				(width 0.1)
				(type default)
			)
			(layer "F.Fab")
		)
		(fp_line
			(start 2.500122 -2.999994)
			(end 2.500122 2.999994)
			(stroke
				(width 0.1)
				(type default)
			)
			(layer "F.Fab")
		)
		(fp_line
			(start -2.500122 2.999994)
			(end -2.500122 -2.999994)
			(stroke
				(width 0.1)
				(type default)
			)
			(layer "F.Fab")
		)
		(fp_line
			(start -2.500122 -2.999994)
			(end 2.500122 -2.999994)
			(stroke
				(width 0.1)
				(type default)
			)
			(layer "F.Fab")
		)
		(fp_poly
			(pts
				(xy -4.218432 -2.783078) (xy -4.218432 -1.767078) (xy -3.202432 -2.275078)
			)
			(stroke
				(width 0)
				(type default)
			)
			(fill yes)
			(layer "F.Fab")
		)
		(pad "1" smd rect
			(at -2.400046 -2.275078 270)
			(size 0.2286 0.6096)
			(layers "F.Cu" "F.Mask" "F.Paste")
			(net "PVDDCR_SOC_P1_VOS1")
		)
		(pad "2" smd rect
			(at -2.400046 -1.82499 270)
			(size 0.2286 0.6096)
			(layers "F.Cu" "F.Mask" "F.Paste")
			(net "GND")
		)
		(pad "3" smd rect
			(at -2.400046 -1.374902 270)
			(size 0.2286 0.6096)
			(layers "F.Cu" "F.Mask" "F.Paste")
			(net "PVDDCR_SOC_P1_VCC1")
		)
		(pad "4" smd rect
			(at -2.400046 -0.925068 270)
			(size 0.2286 0.6096)
			(layers "F.Cu" "F.Mask" "F.Paste")
			(net "PVDDCR_CPU0_P1_PVCC")
		)
		(pad "5" smd rect
			(at -2.400046 -0.47498 270)
			(size 0.2286 0.6096)
			(layers "F.Cu" "F.Mask" "F.Paste")
			(net "GND")
		)
		(pad "6" smd rect
			(at -2.400046 -0.024892 270)
			(size 0.2286 0.6096)
			(layers "F.Cu" "F.Mask" "F.Paste")
			(net "NC_PVDDCR_SOC_P1_GL1_1")
		)
		(pad "7_9-20_24" smd circle
			(at 0 1.150112 270)
			(size 0 0)
			(layers "F.Cu" "F.Mask" "F.Paste")
			(net "GND")
		)
		(pad "10_19" smd rect
			(at 0 2.899918 270)
			(size 0.6096 4.318)
			(layers "F.Cu" "F.Mask" "F.Paste")
			(net "SW_PVDDCR_SOC_P1_SW1")
		)
		(pad "25_29" smd rect
			(at 1.549908 -1.279906 90)
			(size 2.0574 2.3114)
			(layers "F.Cu" "F.Mask" "F.Paste")
			(net "SW_P12V_AUX_PVDDCR_SOC_P1_FLT")
		)
		(pad "30" smd rect
			(at 2.05994 -2.899918 180)
			(size 0.2286 0.6096)
			(layers "F.Cu" "F.Mask" "F.Paste")
			(net "SW_P12V_AUX_PVDDCR_SOC_P1_FLT")
		)
		(pad "31" smd rect
			(at 1.610106 -2.899918 180)
			(size 0.2286 0.6096)
			(layers "F.Cu" "F.Mask" "F.Paste")
			(net "NC_PVDDCR_SOC_P1_DNC1")
		)
		(pad "32" smd rect
			(at 1.160018 -2.899918 180)
			(size 0.2286 0.6096)
			(layers "F.Cu" "F.Mask" "F.Paste")
			(net "SW_PVDDCR_SOC_P1_PH1")
		)
		(pad "33" smd rect
			(at 0.70993 -2.899918 180)
			(size 0.2286 0.6096)
			(layers "F.Cu" "F.Mask" "F.Paste")
			(net "SW_PVDDCR_SOC_P1_BOOT1")
		)
		(pad "34" smd rect
			(at 0.260096 -2.899918 180)
			(size 0.2286 0.6096)
			(layers "F.Cu" "F.Mask" "F.Paste")
			(net "PVDDCR_SOC_P1_PWM1")
		)
		(pad "35" smd rect
			(at -0.189992 -2.899918 180)
			(size 0.2286 0.6096)
			(layers "F.Cu" "F.Mask" "F.Paste")
			(net "PVDDCR_SOC_P1_VCC1")
		)
		(pad "36" smd rect
			(at -0.64008 -2.899918 180)
			(size 0.2286 0.6096)
			(layers "F.Cu" "F.Mask" "F.Paste")
			(net "PVDDCR_SOC_P1_TEMP1")
		)
		(pad "37" smd rect
			(at -1.089914 -2.899918 180)
			(size 0.2286 0.6096)
			(layers "F.Cu" "F.Mask" "F.Paste")
			(net "PVDDCR_SOC_P1_LSET1")
		)
		(pad "38" smd rect
			(at -1.540002 -2.899918 180)
			(size 0.2286 0.6096)
			(layers "F.Cu" "F.Mask" "F.Paste")
			(net "PVDDCR_SOC_P1_IMON1")
		)
		(pad "39" smd rect
			(at -1.99009 -2.899918 180)
			(size 0.2286 0.6096)
			(layers "F.Cu" "F.Mask" "F.Paste")
			(net "PVDDCR_CPU0_P1_VCCS")
		)
		(pad "40" smd rect
			(at -0.87503 -1.27508 180)
			(size 1.7526 1.9558)
			(layers "F.Cu" "F.Mask" "F.Paste")
			(net "GND")
		)
		(pad "41" smd rect
			(at -1.525016 0.249936 90)
			(size 0.3048 0.4572)
			(layers "F.Cu" "F.Mask" "F.Paste")
			(net "NC_PVDDCR_SOC_P1_GL2_1")
		)
		(zone
			(layer "F.Cu")
			(hatch none 0.5)
			(connect_pads
				(clearance 0)
			)
			(min_thickness 0.25)
			(keepout
				(tracks not_allowed)
				(vias allowed)
				(pads allowed)
				(copperpour not_allowed)
				(footprints allowed)
			)
			(placement
				(enabled no)
				(sheetname "")
			)
			(fill
				(thermal_gap 0.5)
				(thermal_bridge_width 0.5)
				(island_removal_mode 0)
			)
			(polygon
				(pts
					(xy 118.185692 -174.467774) (xy 118.185692 -174.17415) (xy 113.185448 -174.17415) (xy 113.185448 -174.467774)
					(xy 113.47577 -174.467774) (xy 117.89537 -174.467774)
				)
			)
		)
		(zone
			(layer "F.Cu")
			(hatch none 0.5)
			(connect_pads
				(clearance 0)
			)
			(min_thickness 0.25)
			(keepout
				(tracks not_allowed)
				(vias allowed)
				(pads allowed)
				(copperpour not_allowed)
				(footprints allowed)
			)
			(placement
				(enabled no)
				(sheetname "")
			)
			(fill
				(thermal_gap 0.5)
				(thermal_bridge_width 0.5)
				(island_removal_mode 0)
			)
			(polygon
				(pts
					(xy 115.6335 -171.677076) (xy 115.6335 -169.619676) (xy 117.4877 -169.619676) (xy 117.4877 -169.860722)
					(xy 117.730016 -169.860722) (xy 117.730016 -169.379138) (xy 113.800636 -169.379138) (xy 113.800636 -169.56405)
					(xy 115.342162 -169.56405) (xy 115.342162 -171.72305) (xy 113.185448 -171.72305) (xy 113.185448 -171.972732)
					(xy 115.369848 -171.972732) (xy 115.6335 -171.70908)
				)
			)
		)
	)
	(footprint ""
		(layer "F.Cu")
		(at 19.05 -364.236 180)
		(property "Reference" "PR232"
			(at 0 0 180)
			(layer "F.SilkS")
			(hide yes)
			(effects
				(font
					(size 1.27 1.27)
				)
			)
		)
		(property "Value" ""
			(at 0 0 180)
			(layer "F.Fab")
			(effects
				(font
					(size 1.27 1.27)
				)
			)
		)
		(duplicate_pad_numbers_are_jumpers no)
		(fp_line
			(start 0.7874 0.4064)
			(end -0.7874 0.4064)
			(stroke
				(width 0.1524)
				(type default)
			)
			(layer "F.SilkS")
		)
		(fp_line
			(start 0.7874 -0.4064)
			(end 0.7874 0.4064)
			(stroke
				(width 0.1524)
				(type default)
			)
			(layer "F.SilkS")
		)
		(fp_line
			(start -0.7874 0.4064)
			(end -0.7874 -0.4064)
			(stroke
				(width 0.1524)
				(type default)
			)
			(layer "F.SilkS")
		)
		(fp_line
			(start -0.7874 -0.4064)
			(end 0.7874 -0.4064)
			(stroke
				(width 0.1524)
				(type default)
			)
			(layer "F.SilkS")
		)
		(fp_line
			(start 0.67945 0.3048)
			(end 0.120396 0.3048)
			(stroke
				(width 0.1)
				(type default)
			)
			(layer "F.Fab")
		)
		(fp_line
			(start 0.67945 -0.3048)
			(end 0.67945 0.3048)
			(stroke
				(width 0.1)
				(type default)
			)
			(layer "F.Fab")
		)
		(fp_line
			(start 0.12065 -0.2794)
			(end 0.12065 -0.3048)
			(stroke
				(width 0.1)
				(type default)
			)
			(layer "F.Fab")
		)
		(fp_line
			(start 0.12065 -0.3048)
			(end 0.67945 -0.3048)
			(stroke
				(width 0.1)
				(type default)
			)
			(layer "F.Fab")
		)
		(fp_line
			(start 0.120396 0.3048)
			(end 0.120396 0.2794)
			(stroke
				(width 0.1)
				(type default)
			)
			(layer "F.Fab")
		)
		(fp_line
			(start 0.120396 0.2794)
			(end -0.12065 0.2794)
			(stroke
				(width 0.1)
				(type default)
			)
			(layer "F.Fab")
		)
		(fp_line
			(start -0.12065 0.3048)
			(end -0.67945 0.3048)
			(stroke
				(width 0.1)
				(type default)
			)
			(layer "F.Fab")
		)
		(fp_line
			(start -0.12065 0.2794)
			(end -0.12065 0.3048)
			(stroke
				(width 0.1)
				(type default)
			)
			(layer "F.Fab")
		)
		(fp_line
			(start -0.12065 -0.2794)
			(end 0.12065 -0.2794)
			(stroke
				(width 0.1)
				(type default)
			)
			(layer "F.Fab")
		)
		(fp_line
			(start -0.12065 -0.305054)
			(end -0.12065 -0.2794)
			(stroke
				(width 0.1)
				(type default)
			)
			(layer "F.Fab")
		)
		(fp_line
			(start -0.67945 0.3048)
			(end -0.67945 -0.305054)
			(stroke
				(width 0.1)
				(type default)
			)
			(layer "F.Fab")
		)
		(fp_line
			(start -0.67945 -0.305054)
			(end -0.12065 -0.305054)
			(stroke
				(width 0.1)
				(type default)
			)
			(layer "F.Fab")
		)
		(pad "1" smd circle
			(at -0.40005 0 180)
			(size 0 0)
			(layers "F.Cu" "F.Mask" "F.Paste")
			(net "P3V3_AUX")
		)
		(pad "2" smd circle
			(at 0.40005 0 180)
			(size 0 0)
			(layers "F.Cu" "F.Mask" "F.Paste")
			(net "PVDDIO_P1_EN_G")
		)
	)
	(footprint ""
		(layer "F.Cu")
		(at 181.71033 -92.672408 90)
		(property "Reference" "R6148"
			(at 0 0 90)
			(layer "F.SilkS")
			(hide yes)
			(effects
				(font
					(size 1.27 1.27)
				)
			)
		)
		(property "Value" ""
			(at 0 0 90)
			(layer "F.Fab")
			(effects
				(font
					(size 1.27 1.27)
				)
			)
		)
		(duplicate_pad_numbers_are_jumpers no)
		(fp_line
			(start 0.7874 -0.4064)
			(end 0.7874 0.4064)
			(stroke
				(width 0.1524)
				(type default)
			)
			(layer "F.SilkS")
		)
		(fp_line
			(start -0.7874 -0.4064)
			(end 0.7874 -0.4064)
			(stroke
				(width 0.1524)
				(type default)
			)
			(layer "F.SilkS")
		)
		(fp_line
			(start 0.7874 0.4064)
			(end -0.7874 0.4064)
			(stroke
				(width 0.1524)
				(type default)
			)
			(layer "F.SilkS")
		)
		(fp_line
			(start -0.7874 0.4064)
			(end -0.7874 -0.4064)
			(stroke
				(width 0.1524)
				(type default)
			)
			(layer "F.SilkS")
		)
		(fp_line
			(start -0.12065 -0.305054)
			(end -0.12065 -0.2794)
			(stroke
				(width 0.1)
				(type default)
			)
			(layer "F.Fab")
		)
		(fp_line
			(start -0.67945 -0.305054)
			(end -0.12065 -0.305054)
			(stroke
				(width 0.1)
				(type default)
			)
			(layer "F.Fab")
		)
		(fp_line
			(start 0.67945 -0.3048)
			(end 0.67945 0.3048)
			(stroke
				(width 0.1)
				(type default)
			)
			(layer "F.Fab")
		)
		(fp_line
			(start 0.12065 -0.3048)
			(end 0.67945 -0.3048)
			(stroke
				(width 0.1)
				(type default)
			)
			(layer "F.Fab")
		)
		(fp_line
			(start 0.12065 -0.2794)
			(end 0.12065 -0.3048)
			(stroke
				(width 0.1)
				(type default)
			)
			(layer "F.Fab")
		)
		(fp_line
			(start -0.12065 -0.2794)
			(end 0.12065 -0.2794)
			(stroke
				(width 0.1)
				(type default)
			)
			(layer "F.Fab")
		)
		(fp_line
			(start 0.120396 0.2794)
			(end -0.12065 0.2794)
			(stroke
				(width 0.1)
				(type default)
			)
			(layer "F.Fab")
		)
		(fp_line
			(start -0.12065 0.2794)
			(end -0.12065 0.3048)
			(stroke
				(width 0.1)
				(type default)
			)
			(layer "F.Fab")
		)
		(fp_line
			(start 0.67945 0.3048)
			(end 0.120396 0.3048)
			(stroke
				(width 0.1)
				(type default)
			)
			(layer "F.Fab")
		)
		(fp_line
			(start 0.120396 0.3048)
			(end 0.120396 0.2794)
			(stroke
				(width 0.1)
				(type default)
			)
			(layer "F.Fab")
		)
		(fp_line
			(start -0.12065 0.3048)
			(end -0.67945 0.3048)
			(stroke
				(width 0.1)
				(type default)
			)
			(layer "F.Fab")
		)
		(fp_line
			(start -0.67945 0.3048)
			(end -0.67945 -0.305054)
			(stroke
				(width 0.1)
				(type default)
			)
			(layer "F.Fab")
		)
		(pad "1" smd circle
			(at -0.40005 0 90)
			(size 0 0)
			(layers "F.Cu" "F.Mask" "F.Paste")
			(net "P1V8_AUX")
		)
		(pad "2" smd circle
			(at 0.40005 0 90)
			(size 0 0)
			(layers "F.Cu" "F.Mask" "F.Paste")
			(net "FAB_BMC_REV_ID0")
		)
	)
	(footprint ""
		(layer "F.Cu")
		(at 194.371722 -76.016866)
		(property "Reference" "R59"
			(at 0 0 0)
			(layer "F.SilkS")
			(hide yes)
			(effects
				(font
					(size 1.27 1.27)
				)
			)
		)
		(property "Value" ""
			(at 0 0 0)
			(layer "F.Fab")
			(effects
				(font
					(size 1.27 1.27)
				)
			)
		)
		(duplicate_pad_numbers_are_jumpers no)
		(fp_line
			(start -0.7874 -0.4064)
			(end 0.7874 -0.4064)
			(stroke
				(width 0.1524)
				(type default)
			)
			(layer "F.SilkS")
		)
		(fp_line
			(start -0.7874 0.4064)
			(end -0.7874 -0.4064)
			(stroke
				(width 0.1524)
				(type default)
			)
			(layer "F.SilkS")
		)
		(fp_line
			(start 0.7874 -0.4064)
			(end 0.7874 0.4064)
			(stroke
				(width 0.1524)
				(type default)
			)
			(layer "F.SilkS")
		)
		(fp_line
			(start 0.7874 0.4064)
			(end -0.7874 0.4064)
			(stroke
				(width 0.1524)
				(type default)
			)
			(layer "F.SilkS")
		)
		(fp_line
			(start -0.67945 -0.305054)
			(end -0.12065 -0.305054)
			(stroke
				(width 0.1)
				(type default)
			)
			(layer "F.Fab")
		)
		(fp_line
			(start -0.67945 0.3048)
			(end -0.67945 -0.305054)
			(stroke
				(width 0.1)
				(type default)
			)
			(layer "F.Fab")
		)
		(fp_line
			(start -0.12065 -0.305054)
			(end -0.12065 -0.2794)
			(stroke
				(width 0.1)
				(type default)
			)
			(layer "F.Fab")
		)
		(fp_line
			(start -0.12065 -0.2794)
			(end 0.12065 -0.2794)
			(stroke
				(width 0.1)
				(type default)
			)
			(layer "F.Fab")
		)
		(fp_line
			(start -0.12065 0.2794)
			(end -0.12065 0.3048)
			(stroke
				(width 0.1)
				(type default)
			)
			(layer "F.Fab")
		)
		(fp_line
			(start -0.12065 0.3048)
			(end -0.67945 0.3048)
			(stroke
				(width 0.1)
				(type default)
			)
			(layer "F.Fab")
		)
		(fp_line
			(start 0.120396 0.2794)
			(end -0.12065 0.2794)
			(stroke
				(width 0.1)
				(type default)
			)
			(layer "F.Fab")
		)
		(fp_line
			(start 0.120396 0.3048)
			(end 0.120396 0.2794)
			(stroke
				(width 0.1)
				(type default)
			)
			(layer "F.Fab")
		)
		(fp_line
			(start 0.12065 -0.3048)
			(end 0.67945 -0.3048)
			(stroke
				(width 0.1)
				(type default)
			)
			(layer "F.Fab")
		)
		(fp_line
			(start 0.12065 -0.2794)
			(end 0.12065 -0.3048)
			(stroke
				(width 0.1)
				(type default)
			)
			(layer "F.Fab")
		)
		(fp_line
			(start 0.67945 -0.3048)
			(end 0.67945 0.3048)
			(stroke
				(width 0.1)
				(type default)
			)
			(layer "F.Fab")
		)
		(fp_line
			(start 0.67945 0.3048)
			(end 0.120396 0.3048)
			(stroke
				(width 0.1)
				(type default)
			)
			(layer "F.Fab")
		)
		(pad "1" smd circle
			(at -0.40005 0)
			(size 0 0)
			(layers "F.Cu" "F.Mask" "F.Paste")
			(net "NCSI_BMC_CRS_DV_R")
		)
		(pad "2" smd circle
			(at 0.40005 0)
			(size 0 0)
			(layers "F.Cu" "F.Mask" "F.Paste")
			(net "RMII_OCP_BMC_CRSDV")
		)
	)
)
